(kicad_pcb
	(version 20260206)
	(generator "pcbnew")
	(generator_version "10.0")
	(general
		(thickness 1.6)
		(legacy_teardrops no)
	)
	(paper "A4")
	(title_block
		(title "01162023_DA0F0TEBIF0_F0T_Expander_BD_F_brd_V02_OCP.brd")
		(comment 1 "Grand Teton / footprints 5569-5573 of 9728")
	)
	(layers
		(0 "F.Cu" signal "TOP")
		(4 "In1.Cu" signal "GND")
		(6 "In2.Cu" signal "VCC")
		(8 "In3.Cu" signal "VCC1")
		(10 "In4.Cu" signal "GND1")
		(12 "In5.Cu" signal "IN1")
		(14 "In6.Cu" signal "GND2")
		(16 "In7.Cu" signal "IN2")
		(18 "In8.Cu" signal "GND3")
		(20 "In9.Cu" signal "IN3")
		(22 "In10.Cu" signal "GND4")
		(24 "In11.Cu" signal "IN4")
		(26 "In12.Cu" signal "GND5")
		(28 "In13.Cu" signal "IN5")
		(30 "In14.Cu" signal "GND6")
		(32 "In15.Cu" signal "IN6")
		(34 "In16.Cu" signal "GND7")
		(2 "B.Cu" signal "BOTTOM")
		(9 "F.Adhes" user "F.Adhesive")
		(11 "B.Adhes" user "B.Adhesive")
		(13 "F.Paste" user "Package Geometry/Pastemask Top")
		(15 "B.Paste" user "Package Geometry/Pastemask Bottom")
		(5 "F.SilkS" user "Ref Des/Silkscreen Top")
		(7 "B.SilkS" user "Ref Des/Silkscreen Bottom")
		(1 "F.Mask" user "Board Geometry/Soldermask Top")
		(3 "B.Mask" user "Board Geometry/Soldermask Bottom")
		(17 "Dwgs.User" user "User.Drawings")
		(19 "Cmts.User" user "User.Comments")
		(21 "Eco1.User" user "User.Eco1")
		(23 "Eco2.User" user "User.Eco2")
		(25 "Edge.Cuts" user "Board Geometry/Outline")
		(27 "Margin" user)
		(31 "F.CrtYd" user "Package Geometry/Place Bound Top")
		(29 "B.CrtYd" user "Package Geometry/Place Bound Bottom")
		(35 "F.Fab" user "Ref Des/Assembly Top")
		(33 "B.Fab" user "Ref Des/Assembly Bottom")
	)
	(footprint ""
		(layer "F.Cu")
		(at 340.561422 -192.44945 180)
		(property "Reference" "R4247"
			(at 0 0 180)
			(layer "F.SilkS")
			(hide yes)
			(effects
				(font
					(size 1.27 1.27)
				)
			)
		)
		(property "Value" ""
			(at 0 0 180)
			(layer "F.Fab")
			(effects
				(font
					(size 1.27 1.27)
				)
			)
		)
		(duplicate_pad_numbers_are_jumpers no)
		(fp_line
			(start 0.7874 0.4064)
			(end -0.7874 0.4064)
			(stroke
				(width 0.1524)
				(type default)
			)
			(layer "F.SilkS")
		)
		(fp_line
			(start 0.7874 -0.4064)
			(end 0.7874 0.4064)
			(stroke
				(width 0.1524)
				(type default)
			)
			(layer "F.SilkS")
		)
		(fp_line
			(start -0.7874 0.4064)
			(end -0.7874 -0.4064)
			(stroke
				(width 0.1524)
				(type default)
			)
			(layer "F.SilkS")
		)
		(fp_line
			(start -0.7874 -0.4064)
			(end 0.7874 -0.4064)
			(stroke
				(width 0.1524)
				(type default)
			)
			(layer "F.SilkS")
		)
		(fp_line
			(start 0.67945 0.3048)
			(end 0.120396 0.3048)
			(stroke
				(width 0.1)
				(type default)
			)
			(layer "F.Fab")
		)
		(fp_line
			(start 0.67945 -0.3048)
			(end 0.67945 0.3048)
			(stroke
				(width 0.1)
				(type default)
			)
			(layer "F.Fab")
		)
		(fp_line
			(start 0.12065 -0.2794)
			(end 0.12065 -0.3048)
			(stroke
				(width 0.1)
				(type default)
			)
			(layer "F.Fab")
		)
		(fp_line
			(start 0.12065 -0.3048)
			(end 0.67945 -0.3048)
			(stroke
				(width 0.1)
				(type default)
			)
			(layer "F.Fab")
		)
		(fp_line
			(start 0.120396 0.3048)
			(end 0.120396 0.2794)
			(stroke
				(width 0.1)
				(type default)
			)
			(layer "F.Fab")
		)
		(fp_line
			(start 0.120396 0.2794)
			(end -0.12065 0.2794)
			(stroke
				(width 0.1)
				(type default)
			)
			(layer "F.Fab")
		)
		(fp_line
			(start -0.12065 0.3048)
			(end -0.67945 0.3048)
			(stroke
				(width 0.1)
				(type default)
			)
			(layer "F.Fab")
		)
		(fp_line
			(start -0.12065 0.2794)
			(end -0.12065 0.3048)
			(stroke
				(width 0.1)
				(type default)
			)
			(layer "F.Fab")
		)
		(fp_line
			(start -0.12065 -0.2794)
			(end 0.12065 -0.2794)
			(stroke
				(width 0.1)
				(type default)
			)
			(layer "F.Fab")
		)
		(fp_line
			(start -0.12065 -0.305054)
			(end -0.12065 -0.2794)
			(stroke
				(width 0.1)
				(type default)
			)
			(layer "F.Fab")
		)
		(fp_line
			(start -0.67945 0.3048)
			(end -0.67945 -0.305054)
			(stroke
				(width 0.1)
				(type default)
			)
			(layer "F.Fab")
		)
		(fp_line
			(start -0.67945 -0.305054)
			(end -0.12065 -0.305054)
			(stroke
				(width 0.1)
				(type default)
			)
			(layer "F.Fab")
		)
		(pad "1" smd circle
			(at -0.40005 0 180)
			(size 0 0)
			(layers "F.Cu" "F.Mask" "F.Paste")
			(net "P3V3_AUX")
		)
		(pad "2" smd circle
			(at 0.40005 0 180)
			(size 0 0)
			(layers "F.Cu" "F.Mask" "F.Paste")
			(net "FM_CPU_CATERR_MSMI_LVT3_N")
		)
	)
	(footprint ""
		(layer "F.Cu")
		(at 370.947188 -54.3941)
		(property "Reference" "PU39"
			(at -1.560576 2.93878 0)
			(unlocked yes)
			(layer "F.SilkS")
			(effects
				(font
					(size 0.7874 0.5842)
					(thickness 0.1524)
				)
				(justify left)
			)
		)
		(property "Value" ""
			(at 0 0 0)
			(layer "F.Fab")
			(effects
				(font
					(size 1.27 1.27)
				)
			)
		)
		(duplicate_pad_numbers_are_jumpers no)
		(fp_line
			(start -1.943608 -1.549908)
			(end 1.943608 -1.549908)
			(stroke
				(width 0.1524)
				(type default)
			)
			(layer "F.SilkS")
		)
		(fp_line
			(start -1.943608 1.549908)
			(end -1.943608 -1.549908)
			(stroke
				(width 0.1524)
				(type default)
			)
			(layer "F.SilkS")
		)
		(fp_line
			(start 1.943608 -1.549908)
			(end 1.943608 1.549908)
			(stroke
				(width 0.1524)
				(type default)
			)
			(layer "F.SilkS")
		)
		(fp_line
			(start 1.943608 1.549908)
			(end -1.943608 1.549908)
			(stroke
				(width 0.1524)
				(type default)
			)
			(layer "F.SilkS")
		)
		(fp_poly
			(pts
				(xy -2.019808 -1.549908) (xy -1.257808 -1.549908) (xy -1.257808 -1.880108) (xy -2.019808 -1.880108)
			)
			(stroke
				(width 0)
				(type default)
			)
			(fill yes)
			(layer "F.SilkS")
		)
		(fp_line
			(start -1.549908 -1.549908)
			(end 1.549908 -1.549908)
			(stroke
				(width 0.1)
				(type default)
			)
			(layer "F.Fab")
		)
		(fp_line
			(start -1.549908 1.549908)
			(end -1.549908 -1.549908)
			(stroke
				(width 0.1)
				(type default)
			)
			(layer "F.Fab")
		)
		(fp_line
			(start 1.549908 -1.549908)
			(end 1.549908 1.549908)
			(stroke
				(width 0.1)
				(type default)
			)
			(layer "F.Fab")
		)
		(fp_line
			(start 1.549908 1.549908)
			(end -1.549908 1.549908)
			(stroke
				(width 0.1)
				(type default)
			)
			(layer "F.Fab")
		)
		(fp_poly
			(pts
				(xy -2.019808 -1.549908) (xy -1.257808 -1.549908) (xy -1.257808 -1.880108) (xy -2.019808 -1.880108)
			)
			(stroke
				(width 0)
				(type default)
			)
			(fill yes)
			(layer "F.Fab")
		)
		(pad "1" smd rect
			(at -1.500124 -1.249934 270)
			(size 0.2794 0.6096)
			(layers "F.Cu" "F.Mask" "F.Paste")
			(net "P12V_SSD12_R")
		)
		(pad "2" smd rect
			(at -1.500124 -0.750062 270)
			(size 0.2794 0.6096)
			(layers "F.Cu" "F.Mask" "F.Paste")
			(net "P12V_SSD12_R")
		)
		(pad "3" smd rect
			(at -1.500124 -0.249936 270)
			(size 0.2794 0.6096)
			(layers "F.Cu" "F.Mask" "F.Paste")
			(net "P12V_SSD12_R")
		)
		(pad "4" smd rect
			(at -1.500124 0.249936 270)
			(size 0.2794 0.6096)
			(layers "F.Cu" "F.Mask" "F.Paste")
			(net "P12V_SSD12_R")
		)
		(pad "5" smd rect
			(at -1.500124 0.750062 270)
			(size 0.2794 0.6096)
			(layers "F.Cu" "F.Mask" "F.Paste")
			(net "P12V_SSD12_R")
		)
		(pad "6" smd rect
			(at -1.500124 1.249934 270)
			(size 0.2794 0.6096)
			(layers "F.Cu" "F.Mask" "F.Paste")
			(net "GND")
		)
		(pad "7" smd rect
			(at 1.500124 1.249934 270)
			(size 0.2794 0.6096)
			(layers "F.Cu" "F.Mask" "F.Paste")
			(net "P12V_SSD12_SS")
		)
		(pad "8" smd rect
			(at 1.500124 0.750062 270)
			(size 0.2794 0.6096)
			(layers "F.Cu" "F.Mask" "F.Paste")
			(net "PWRGD_P12V_SSD12")
		)
		(pad "9" smd rect
			(at 1.500124 0.249936 270)
			(size 0.2794 0.6096)
			(layers "F.Cu" "F.Mask" "F.Paste")
			(net "P12V_SSD12_OCP")
		)
		(pad "10" smd rect
			(at 1.500124 -0.249936 270)
			(size 0.2794 0.6096)
			(layers "F.Cu" "F.Mask" "F.Paste")
			(net "P5V_AUX")
		)
		(pad "11" smd rect
			(at 1.500124 -0.750062 270)
			(size 0.2794 0.6096)
			(layers "F.Cu" "F.Mask" "F.Paste")
			(net "SSD12_PWR_EN_R")
		)
		(pad "12" smd rect
			(at 1.500124 -1.249934 270)
			(size 0.2794 0.6096)
			(layers "F.Cu" "F.Mask" "F.Paste")
			(net "P12V_AUX")
		)
		(pad "13" smd rect
			(at 0 0)
			(size 1.9812 2.7178)
			(layers "F.Cu" "F.Mask" "F.Paste")
			(net "P12V_AUX")
		)
		(zone
			(layer "F.Cu")
			(hatch none 0.5)
			(connect_pads
				(clearance 0)
			)
			(min_thickness 0.25)
			(keepout
				(tracks not_allowed)
				(vias allowed)
				(pads allowed)
				(copperpour not_allowed)
				(footprints allowed)
			)
			(placement
				(enabled no)
				(sheetname "")
			)
			(fill
				(thermal_gap 0.5)
				(thermal_bridge_width 0.5)
				(island_removal_mode 0)
			)
			(polygon
				(pts
					(xy 372.090188 -55.9435) (xy 372.090188 -55.8165) (xy 372.090188 -52.8447) (xy 372.090188 -52.844192)
					(xy 369.804188 -52.844192) (xy 369.804188 -52.8447) (xy 369.804188 -52.9717) (xy 369.804188 -54.3941)
					(xy 369.905788 -54.3941) (xy 369.905788 -52.9717) (xy 371.988588 -52.9717) (xy 371.988588 -55.8165)
					(xy 369.905788 -55.8165) (xy 369.905788 -54.4195) (xy 369.804188 -54.4195) (xy 369.804188 -55.8165)
					(xy 369.804188 -55.9435) (xy 369.804188 -55.944008) (xy 372.090188 -55.944008)
				)
			)
		)
	)
	(footprint ""
		(layer "F.Cu")
		(at 259.092446 -338.413344 -90)
		(property "Reference" "R6790"
			(at 0 0 270)
			(layer "F.SilkS")
			(hide yes)
			(effects
				(font
					(size 1.27 1.27)
				)
			)
		)
		(property "Value" ""
			(at 0 0 270)
			(layer "F.Fab")
			(effects
				(font
					(size 1.27 1.27)
				)
			)
		)
		(duplicate_pad_numbers_are_jumpers no)
		(fp_line
			(start -0.7874 0.4064)
			(end -0.7874 -0.4064)
			(stroke
				(width 0.1524)
				(type default)
			)
			(layer "F.SilkS")
		)
		(fp_line
			(start 0.7874 0.4064)
			(end -0.7874 0.4064)
			(stroke
				(width 0.1524)
				(type default)
			)
			(layer "F.SilkS")
		)
		(fp_line
			(start -0.7874 -0.4064)
			(end 0.7874 -0.4064)
			(stroke
				(width 0.1524)
				(type default)
			)
			(layer "F.SilkS")
		)
		(fp_line
			(start 0.7874 -0.4064)
			(end 0.7874 0.4064)
			(stroke
				(width 0.1524)
				(type default)
			)
			(layer "F.SilkS")
		)
		(fp_line
			(start -0.67945 0.3048)
			(end -0.67945 -0.305054)
			(stroke
				(width 0.1)
				(type default)
			)
			(layer "F.Fab")
		)
		(fp_line
			(start -0.12065 0.3048)
			(end -0.67945 0.3048)
			(stroke
				(width 0.1)
				(type default)
			)
			(layer "F.Fab")
		)
		(fp_line
			(start 0.120396 0.3048)
			(end 0.120396 0.2794)
			(stroke
				(width 0.1)
				(type default)
			)
			(layer "F.Fab")
		)
		(fp_line
			(start 0.67945 0.3048)
			(end 0.120396 0.3048)
			(stroke
				(width 0.1)
				(type default)
			)
			(layer "F.Fab")
		)
		(fp_line
			(start -0.12065 0.2794)
			(end -0.12065 0.3048)
			(stroke
				(width 0.1)
				(type default)
			)
			(layer "F.Fab")
		)
		(fp_line
			(start 0.120396 0.2794)
			(end -0.12065 0.2794)
			(stroke
				(width 0.1)
				(type default)
			)
			(layer "F.Fab")
		)
		(fp_line
			(start -0.12065 -0.2794)
			(end 0.12065 -0.2794)
			(stroke
				(width 0.1)
				(type default)
			)
			(layer "F.Fab")
		)
		(fp_line
			(start 0.12065 -0.2794)
			(end 0.12065 -0.3048)
			(stroke
				(width 0.1)
				(type default)
			)
			(layer "F.Fab")
		)
		(fp_line
			(start 0.12065 -0.3048)
			(end 0.67945 -0.3048)
			(stroke
				(width 0.1)
				(type default)
			)
			(layer "F.Fab")
		)
		(fp_line
			(start 0.67945 -0.3048)
			(end 0.67945 0.3048)
			(stroke
				(width 0.1)
				(type default)
			)
			(layer "F.Fab")
		)
		(fp_line
			(start -0.67945 -0.305054)
			(end -0.12065 -0.305054)
			(stroke
				(width 0.1)
				(type default)
			)
			(layer "F.Fab")
		)
		(fp_line
			(start -0.12065 -0.305054)
			(end -0.12065 -0.2794)
			(stroke
				(width 0.1)
				(type default)
			)
			(layer "F.Fab")
		)
		(pad "1" smd circle
			(at -0.40005 0 270)
			(size 0 0)
			(layers "F.Cu" "F.Mask" "F.Paste")
			(net "P3V3_AUX")
		)
		(pad "2" smd circle
			(at 0.40005 0 270)
			(size 0 0)
			(layers "F.Cu" "F.Mask" "F.Paste")
			(net "OC_P2V5_COMP")
		)
	)
	(footprint ""
		(layer "F.Cu")
		(at 261.55777 -27.006296 -90)
		(property "Reference" "PR7117"
			(at 0 0 270)
			(layer "F.SilkS")
			(hide yes)
			(effects
				(font
					(size 1.27 1.27)
				)
			)
		)
		(property "Value" ""
			(at 0 0 270)
			(layer "F.Fab")
			(effects
				(font
					(size 1.27 1.27)
				)
			)
		)
		(duplicate_pad_numbers_are_jumpers no)
		(fp_line
			(start -0.7874 0.4064)
			(end -0.7874 -0.4064)
			(stroke
				(width 0.1524)
				(type default)
			)
			(layer "F.SilkS")
		)
		(fp_line
			(start 0.7874 0.4064)
			(end -0.7874 0.4064)
			(stroke
				(width 0.1524)
				(type default)
			)
			(layer "F.SilkS")
		)
		(fp_line
			(start -0.7874 -0.4064)
			(end 0.7874 -0.4064)
			(stroke
				(width 0.1524)
				(type default)
			)
			(layer "F.SilkS")
		)
		(fp_line
			(start 0.7874 -0.4064)
			(end 0.7874 0.4064)
			(stroke
				(width 0.1524)
				(type default)
			)
			(layer "F.SilkS")
		)
		(fp_line
			(start -0.67945 0.3048)
			(end -0.67945 -0.305054)
			(stroke
				(width 0.1)
				(type default)
			)
			(layer "F.Fab")
		)
		(fp_line
			(start -0.12065 0.3048)
			(end -0.67945 0.3048)
			(stroke
				(width 0.1)
				(type default)
			)
			(layer "F.Fab")
		)
		(fp_line
			(start 0.120396 0.3048)
			(end 0.120396 0.2794)
			(stroke
				(width 0.1)
				(type default)
			)
			(layer "F.Fab")
		)
		(fp_line
			(start 0.67945 0.3048)
			(end 0.120396 0.3048)
			(stroke
				(width 0.1)
				(type default)
			)
			(layer "F.Fab")
		)
		(fp_line
			(start -0.12065 0.2794)
			(end -0.12065 0.3048)
			(stroke
				(width 0.1)
				(type default)
			)
			(layer "F.Fab")
		)
		(fp_line
			(start 0.120396 0.2794)
			(end -0.12065 0.2794)
			(stroke
				(width 0.1)
				(type default)
			)
			(layer "F.Fab")
		)
		(fp_line
			(start -0.12065 -0.2794)
			(end 0.12065 -0.2794)
			(stroke
				(width 0.1)
				(type default)
			)
			(layer "F.Fab")
		)
		(fp_line
			(start 0.12065 -0.2794)
			(end 0.12065 -0.3048)
			(stroke
				(width 0.1)
				(type default)
			)
			(layer "F.Fab")
		)
		(fp_line
			(start 0.12065 -0.3048)
			(end 0.67945 -0.3048)
			(stroke
				(width 0.1)
				(type default)
			)
			(layer "F.Fab")
		)
		(fp_line
			(start 0.67945 -0.3048)
			(end 0.67945 0.3048)
			(stroke
				(width 0.1)
				(type default)
			)
			(layer "F.Fab")
		)
		(fp_line
			(start -0.67945 -0.305054)
			(end -0.12065 -0.305054)
			(stroke
				(width 0.1)
				(type default)
			)
			(layer "F.Fab")
		)
		(fp_line
			(start -0.12065 -0.305054)
			(end -0.12065 -0.2794)
			(stroke
				(width 0.1)
				(type default)
			)
			(layer "F.Fab")
		)
		(pad "1" smd circle
			(at -0.40005 0 270)
			(size 0 0)
			(layers "F.Cu" "F.Mask" "F.Paste")
			(net "P3V3_SSD9_CO_MODE")
		)
		(pad "2" smd circle
			(at 0.40005 0 270)
			(size 0 0)
			(layers "F.Cu" "F.Mask" "F.Paste")
			(net "GND")
		)
	)
	(footprint ""
		(layer "F.Cu")
		(at 34.211006 -61.386974)
		(property "Reference" "R4486"
			(at 0 0 0)
			(layer "F.SilkS")
			(hide yes)
			(effects
				(font
					(size 1.27 1.27)
				)
			)
		)
		(property "Value" ""
			(at 0 0 0)
			(layer "F.Fab")
			(effects
				(font
					(size 1.27 1.27)
				)
			)
		)
		(duplicate_pad_numbers_are_jumpers no)
		(fp_line
			(start -0.7874 -0.4064)
			(end 0.7874 -0.4064)
			(stroke
				(width 0.1524)
				(type default)
			)
			(layer "F.SilkS")
		)
		(fp_line
			(start -0.7874 0.4064)
			(end -0.7874 -0.4064)
			(stroke
				(width 0.1524)
				(type default)
			)
			(layer "F.SilkS")
		)
		(fp_line
			(start 0.7874 -0.4064)
			(end 0.7874 0.4064)
			(stroke
				(width 0.1524)
				(type default)
			)
			(layer "F.SilkS")
		)
		(fp_line
			(start 0.7874 0.4064)
			(end -0.7874 0.4064)
			(stroke
				(width 0.1524)
				(type default)
			)
			(layer "F.SilkS")
		)
		(fp_line
			(start -0.67945 -0.305054)
			(end -0.12065 -0.305054)
			(stroke
				(width 0.1)
				(type default)
			)
			(layer "F.Fab")
		)
		(fp_line
			(start -0.67945 0.3048)
			(end -0.67945 -0.305054)
			(stroke
				(width 0.1)
				(type default)
			)
			(layer "F.Fab")
		)
		(fp_line
			(start -0.12065 -0.305054)
			(end -0.12065 -0.2794)
			(stroke
				(width 0.1)
				(type default)
			)
			(layer "F.Fab")
		)
		(fp_line
			(start -0.12065 -0.2794)
			(end 0.12065 -0.2794)
			(stroke
				(width 0.1)
				(type default)
			)
			(layer "F.Fab")
		)
		(fp_line
			(start -0.12065 0.2794)
			(end -0.12065 0.3048)
			(stroke
				(width 0.1)
				(type default)
			)
			(layer "F.Fab")
		)
		(fp_line
			(start -0.12065 0.3048)
			(end -0.67945 0.3048)
			(stroke
				(width 0.1)
				(type default)
			)
			(layer "F.Fab")
		)
		(fp_line
			(start 0.120396 0.2794)
			(end -0.12065 0.2794)
			(stroke
				(width 0.1)
				(type default)
			)
			(layer "F.Fab")
		)
		(fp_line
			(start 0.120396 0.3048)
			(end 0.120396 0.2794)
			(stroke
				(width 0.1)
				(type default)
			)
			(layer "F.Fab")
		)
		(fp_line
			(start 0.12065 -0.3048)
			(end 0.67945 -0.3048)
			(stroke
				(width 0.1)
				(type default)
			)
			(layer "F.Fab")
		)
		(fp_line
			(start 0.12065 -0.2794)
			(end 0.12065 -0.3048)
			(stroke
				(width 0.1)
				(type default)
			)
			(layer "F.Fab")
		)
		(fp_line
			(start 0.67945 -0.3048)
			(end 0.67945 0.3048)
			(stroke
				(width 0.1)
				(type default)
			)
			(layer "F.Fab")
		)
		(fp_line
			(start 0.67945 0.3048)
			(end 0.120396 0.3048)
			(stroke
				(width 0.1)
				(type default)
			)
			(layer "F.Fab")
		)
		(pad "1" smd circle
			(at -0.40005 0)
			(size 0 0)
			(layers "F.Cu" "F.Mask" "F.Paste")
			(net "PWRGD_P3V3_SSD1")
		)
		(pad "2" smd circle
			(at 0.40005 0)
			(size 0 0)
			(layers "F.Cu" "F.Mask" "F.Paste")
			(net "PWRGD_P3V3_SSD1_R")
		)
	)
)
